# BASEBOARD_FAB2 (Tioga Pass) — schematic netlist excerpt (pin names and nets, part order shuffled) for the footprints in the layout excerpt that follows; sources: Cadence DE-HDL packaged netlist, KiCad conversion of Wiwynn_Tioga_Pass_MB.brd

EU8A1  PXE1110B  IC  pkg QFN  page 235
  DNC(0)  = NC
  DNC(1)  = NC
  BPWM1  = VR_P1V05_PCH_STBY_PWM1
  DNC(2)  = NC
  APWM1  = VR_PVNN_PCH_PWM1
  SDA  = SMB_VR_STBY_LVC3_SDA
  SCL  = SMB_VR_STBY_LVC3_SCL
  RESET_N  = NC
  AVRRDY  = PWRGD_PVNN_PCH_R
  AVREN  = VR_PVNN_PCH_VREN
  VRHOT_N  = IRQ_PVNN_PCH_VRHOT_N
  PINALRT_N  = PU_PVNN_PCH_PINALRT_N
  MP0  = VID_PCH_CORE_PVNN_AUX_VID_0
  MP1  = VID_PCH_CORE_PVNN_AUX_VID_1
  VCLK  = PU_PVNN_PCH_VCLK
  VDIO  = PU_PVNN_PCH_VDIO
  VALRT_N  = NC
  MP2  = NC
  AVSEN  = VR_PVNN_PCH_AVSP
  AVREF  = VSENSE_PVNN_PCH_STBY_AVSN
  AIREF1  = VR_PVNN_PCH_AIREF1
  AISEN1  = ISENSE_PVNN_PCH_PH1_IMON
  GND(1)  = GND
  DNC(3)  = NC
  BIREF1  = VR_P1V05_PCH_BIREF1
  BISEN1  = ISENSE_P1V05_PCH_STBY_PH1_IMON
  GND(0)  = GND
  DNC(4)  = NC
  BVSEN  = VR_P1V05_PCH_STBY_AVSP
  BVREF  = VSENSE_P1V05_PCH_STBY_AVSN
  MP3  = NC
  MP4  = PU_VR_PVNN_PCH_FAULT1
  XADDR2  = VR_PVNN_PCH_XADDR2
  BTSEN  = A_TSENSE_P1V05_PCH_STBY_TMON
  ATSEN  = A_TSENSE_PVNN_PCH_TMON
  XADDR1  = VR_PVNN_PCH_XADDR1
  VINSEN  = VR_PVNN_PCH_VINSEN
  IINSEN  = NC
  VDD  = VR_PVNN_PCH_VDD
  VD12  = VR_PVNN_P1V05_PCH_VD12
  THPAD  = GND

(kicad_pcb
	(version 20260206)
	(generator "pcbnew")
	(generator_version "10.0")
	(general
		(thickness 1.6)
		(legacy_teardrops no)
	)
	(paper "A4")
	(title_block
		(title "Wiwynn_Tioga_Pass_MB.brd")
		(comment 1 "Tioga Pass / footprint 1719 of 4770 (EU8A1), pads 1-17 of 41")
	)
	(layers
		(0 "F.Cu" signal "TOP")
		(4 "In1.Cu" signal "L2GND")
		(6 "In2.Cu" signal "L3")
		(8 "In3.Cu" signal "L4GND")
		(10 "In4.Cu" signal "L5")
		(12 "In5.Cu" signal "L6GND")
		(14 "In6.Cu" signal "L7VCC")
		(16 "In7.Cu" signal "L8VCC")
		(18 "In8.Cu" signal "L9GND")
		(20 "In9.Cu" signal "L10")
		(22 "In10.Cu" signal "L11GND")
		(24 "In11.Cu" signal "L12")
		(26 "In12.Cu" signal "L13GND")
		(2 "B.Cu" signal "BOTTOM")
		(9 "F.Adhes" user "F.Adhesive")
		(11 "B.Adhes" user "B.Adhesive")
		(13 "F.Paste" user "Package Geometry/Pastemask Top")
		(15 "B.Paste" user "Package Geometry/Pastemask Bottom")
		(5 "F.SilkS" user "Ref Des/Silkscreen Top")
		(7 "B.SilkS" user "Ref Des/Silkscreen Bottom")
		(1 "F.Mask" user "Board Geometry/Soldermask Top")
		(3 "B.Mask" user "Board Geometry/Soldermask Bottom")
		(17 "Dwgs.User" user "User.Drawings")
		(19 "Cmts.User" user "User.Comments")
		(21 "Eco1.User" user "User.Eco1")
		(23 "Eco2.User" user "User.Eco2")
		(25 "Edge.Cuts" user "Board Geometry/Outline")
		(27 "Margin" user)
		(31 "F.CrtYd" user "Package Geometry/Place Bound Top")
		(29 "B.CrtYd" user "Package Geometry/Place Bound Bottom")
		(35 "F.Fab" user "Ref Des/Assembly Top")
		(33 "B.Fab" user "Ref Des/Assembly Bottom")
	)
	(footprint ""
		(layer "F.Cu")
		(at 395.7828 -153.797 90)
		(property "Reference" "EU8A1"
			(at 3.40233 -2.7178 0)
			(unlocked yes)
			(layer "F.SilkS")
			(effects
				(font
					(size 0.7874 0.5842)
					(thickness 0.1524)
				)
				(justify left)
			)
		)
		(property "Value" ""
			(at 0 0 90)
			(layer "F.Fab")
			(effects
				(font
					(size 1.27 1.27)
				)
			)
		)
		(duplicate_pad_numbers_are_jumpers no)
		(pad "1" smd custom
			(at -2.4511 -1.800098 90)
			(size 0.0508 0.0508)
			(layers "F.Cu" "F.Mask" "F.Paste")
			(net "Net_351")
			(options
				(clearance outline)
				(anchor circle)
			)
			(primitives
				(gr_poly
					(pts
						(arc
							(start 0.254 -0.1016)
							(mid 0.3556 0)
							(end 0.254 0.1016)
						)
						(xy -0.3556 0.1016) (xy -0.3556 -0.1016)
					)
					(width 0)
					(fill yes)
				)
			)
		)
		(pad "2" smd custom
			(at -2.4511 -1.400048 90)
			(size 0.0508 0.0508)
			(layers "F.Cu" "F.Mask" "F.Paste")
			(net "Net_352")
			(options
				(clearance outline)
				(anchor circle)
			)
			(primitives
				(gr_poly
					(pts
						(arc
							(start 0.254 -0.1016)
							(mid 0.3556 0)
							(end 0.254 0.1016)
						)
						(xy -0.3556 0.1016) (xy -0.3556 -0.1016)
					)
					(width 0)
					(fill yes)
				)
			)
		)
		(pad "3" smd custom
			(at -2.4511 -0.999998 90)
			(size 0.0508 0.0508)
			(layers "F.Cu" "F.Mask" "F.Paste")
			(net "VR_P1V05_PCH_STBY_PWM1")
			(options
				(clearance outline)
				(anchor circle)
			)
			(primitives
				(gr_poly
					(pts
						(arc
							(start 0.254 -0.1016)
							(mid 0.3556 0)
							(end 0.254 0.1016)
						)
						(xy -0.3556 0.1016) (xy -0.3556 -0.1016)
					)
					(width 0)
					(fill yes)
				)
			)
		)
		(pad "4" smd custom
			(at -2.4511 -0.599948 90)
			(size 0.0508 0.0508)
			(layers "F.Cu" "F.Mask" "F.Paste")
			(net "Net_353")
			(options
				(clearance outline)
				(anchor circle)
			)
			(primitives
				(gr_poly
					(pts
						(arc
							(start 0.254 -0.1016)
							(mid 0.3556 0)
							(end 0.254 0.1016)
						)
						(xy -0.3556 0.1016) (xy -0.3556 -0.1016)
					)
					(width 0)
					(fill yes)
				)
			)
		)
		(pad "5" smd custom
			(at -2.4511 -0.199898 90)
			(size 0.0508 0.0508)
			(layers "F.Cu" "F.Mask" "F.Paste")
			(net "VR_PVNN_PCH_PWM1")
			(options
				(clearance outline)
				(anchor circle)
			)
			(primitives
				(gr_poly
					(pts
						(arc
							(start 0.254 -0.1016)
							(mid 0.3556 0)
							(end 0.254 0.1016)
						)
						(xy -0.3556 0.1016) (xy -0.3556 -0.1016)
					)
					(width 0)
					(fill yes)
				)
			)
		)
		(pad "6" smd custom
			(at -2.4511 0.199898 90)
			(size 0.0508 0.0508)
			(layers "F.Cu" "F.Mask" "F.Paste")
			(net "SMB_VR_STBY_LVC3_SDA")
			(options
				(clearance outline)
				(anchor circle)
			)
			(primitives
				(gr_poly
					(pts
						(arc
							(start 0.254 -0.1016)
							(mid 0.3556 0)
							(end 0.254 0.1016)
						)
						(xy -0.3556 0.1016) (xy -0.3556 -0.1016)
					)
					(width 0)
					(fill yes)
				)
			)
		)
		(pad "7" smd custom
			(at -2.4511 0.599948 90)
			(size 0.0508 0.0508)
			(layers "F.Cu" "F.Mask" "F.Paste")
			(net "SMB_VR_STBY_LVC3_SCL")
			(options
				(clearance outline)
				(anchor circle)
			)
			(primitives
				(gr_poly
					(pts
						(arc
							(start 0.254 -0.1016)
							(mid 0.3556 0)
							(end 0.254 0.1016)
						)
						(xy -0.3556 0.1016) (xy -0.3556 -0.1016)
					)
					(width 0)
					(fill yes)
				)
			)
		)
		(pad "8" smd custom
			(at -2.4511 0.999998 90)
			(size 0.0508 0.0508)
			(layers "F.Cu" "F.Mask" "F.Paste")
			(net "Net_289")
			(options
				(clearance outline)
				(anchor circle)
			)
			(primitives
				(gr_poly
					(pts
						(arc
							(start 0.254 -0.1016)
							(mid 0.3556 0)
							(end 0.254 0.1016)
						)
						(xy -0.3556 0.1016) (xy -0.3556 -0.1016)
					)
					(width 0)
					(fill yes)
				)
			)
		)
		(pad "9" smd custom
			(at -2.4511 1.400048 90)
			(size 0.0508 0.0508)
			(layers "F.Cu" "F.Mask" "F.Paste")
			(net "PWRGD_PVNN_PCH_R")
			(options
				(clearance outline)
				(anchor circle)
			)
			(primitives
				(gr_poly
					(pts
						(arc
							(start 0.254 -0.1016)
							(mid 0.3556 0)
							(end 0.254 0.1016)
						)
						(xy -0.3556 0.1016) (xy -0.3556 -0.1016)
					)
					(width 0)
					(fill yes)
				)
			)
		)
		(pad "10" smd custom
			(at -2.4511 1.800098 90)
			(size 0.0508 0.0508)
			(layers "F.Cu" "F.Mask" "F.Paste")
			(net "VR_PVNN_PCH_VREN")
			(options
				(clearance outline)
				(anchor circle)
			)
			(primitives
				(gr_poly
					(pts
						(arc
							(start 0.254 -0.1016)
							(mid 0.3556 0)
							(end 0.254 0.1016)
						)
						(xy -0.3556 0.1016) (xy -0.3556 -0.1016)
					)
					(width 0)
					(fill yes)
				)
			)
		)
		(pad "11" smd custom
			(at -1.800098 2.4511 90)
			(size 0.0508 0.0508)
			(layers "F.Cu" "F.Mask" "F.Paste")
			(net "IRQ_PVNN_PCH_VRHOT_N")
			(options
				(clearance outline)
				(anchor circle)
			)
			(primitives
				(gr_poly
					(pts
						(arc
							(start -0.1016 -0.254)
							(mid 0 -0.3556)
							(end 0.1016 -0.254)
						)
						(xy 0.1016 0.3556) (xy -0.1016 0.3556)
					)
					(width 0)
					(fill yes)
				)
			)
		)
		(pad "12" smd custom
			(at -1.400048 2.4511 90)
			(size 0.0508 0.0508)
			(layers "F.Cu" "F.Mask" "F.Paste")
			(net "PU_PVNN_PCH_PINALRT_N")
			(options
				(clearance outline)
				(anchor circle)
			)
			(primitives
				(gr_poly
					(pts
						(arc
							(start -0.1016 -0.254)
							(mid 0 -0.3556)
							(end 0.1016 -0.254)
						)
						(xy 0.1016 0.3556) (xy -0.1016 0.3556)
					)
					(width 0)
					(fill yes)
				)
			)
		)
		(pad "13" smd custom
			(at -0.999998 2.4511 90)
			(size 0.0508 0.0508)
			(layers "F.Cu" "F.Mask" "F.Paste")
			(net "VID_PCH_CORE_PVNN_AUX_VID_0")
			(options
				(clearance outline)
				(anchor circle)
			)
			(primitives
				(gr_poly
					(pts
						(arc
							(start -0.1016 -0.254)
							(mid 0 -0.3556)
							(end 0.1016 -0.254)
						)
						(xy 0.1016 0.3556) (xy -0.1016 0.3556)
					)
					(width 0)
					(fill yes)
				)
			)
		)
		(pad "14" smd custom
			(at -0.599948 2.4511 90)
			(size 0.0508 0.0508)
			(layers "F.Cu" "F.Mask" "F.Paste")
			(net "VID_PCH_CORE_PVNN_AUX_VID_1")
			(options
				(clearance outline)
				(anchor circle)
			)
			(primitives
				(gr_poly
					(pts
						(arc
							(start -0.1016 -0.254)
							(mid 0 -0.3556)
							(end 0.1016 -0.254)
						)
						(xy 0.1016 0.3556) (xy -0.1016 0.3556)
					)
					(width 0)
					(fill yes)
				)
			)
		)
		(pad "15" smd custom
			(at -0.199898 2.4511 90)
			(size 0.0508 0.0508)
			(layers "F.Cu" "F.Mask" "F.Paste")
			(net "PU_PVNN_PCH_VCLK")
			(options
				(clearance outline)
				(anchor circle)
			)
			(primitives
				(gr_poly
					(pts
						(arc
							(start -0.1016 -0.254)
							(mid 0 -0.3556)
							(end 0.1016 -0.254)
						)
						(xy 0.1016 0.3556) (xy -0.1016 0.3556)
					)
					(width 0)
					(fill yes)
				)
			)
		)
		(pad "16" smd custom
			(at 0.199898 2.4511 90)
			(size 0.0508 0.0508)
			(layers "F.Cu" "F.Mask" "F.Paste")
			(net "PU_PVNN_PCH_VDIO")
			(options
				(clearance outline)
				(anchor circle)
			)
			(primitives
				(gr_poly
					(pts
						(arc
							(start -0.1016 -0.254)
							(mid 0 -0.3556)
							(end 0.1016 -0.254)
						)
						(xy 0.1016 0.3556) (xy -0.1016 0.3556)
					)
					(width 0)
					(fill yes)
				)
			)
		)
		(pad "17" smd custom
			(at 0.599948 2.4511 90)
			(size 0.0508 0.0508)
			(layers "F.Cu" "F.Mask" "F.Paste")
			(net "Net_267")
			(options
				(clearance outline)
				(anchor circle)
			)
			(primitives
				(gr_poly
					(pts
						(arc
							(start -0.1016 -0.254)
							(mid 0 -0.3556)
							(end 0.1016 -0.254)
						)
						(xy 0.1016 0.3556) (xy -0.1016 0.3556)
					)
					(width 0)
					(fill yes)
				)
			)
		)
	)
)
